(kicad_pcb
	(version 20260206)
	(generator "pcbnew")
	(generator_version "10.0")
	(general
		(thickness 1.6)
		(legacy_teardrops no)
	)
	(paper "A4")
	(title_block
		(title "04192023_DAF0TMB3IC0_F0TG_MB_C_brd_V02_OCP.brd")
		(comment 1 "Grand Teton / footprints 1057-1063 of 8354")
	)
	(layers
		(0 "F.Cu" signal "TOP")
		(4 "In1.Cu" signal "GND")
		(6 "In2.Cu" signal "IN1")
		(8 "In3.Cu" signal "GND1")
		(10 "In4.Cu" signal "IN2")
		(12 "In5.Cu" signal "GND2")
		(14 "In6.Cu" signal "IN3")
		(16 "In7.Cu" signal "GND3")
		(18 "In8.Cu" signal "VCC")
		(20 "In9.Cu" signal "VCC1")
		(22 "In10.Cu" signal "GND4")
		(24 "In11.Cu" signal "IN4")
		(26 "In12.Cu" signal "GND5")
		(28 "In13.Cu" signal "IN5")
		(30 "In14.Cu" signal "GND6")
		(32 "In15.Cu" signal "IN6")
		(34 "In16.Cu" signal "GND7")
		(2 "B.Cu" signal "BOTTOM")
		(9 "F.Adhes" user "F.Adhesive")
		(11 "B.Adhes" user "B.Adhesive")
		(13 "F.Paste" user "Package Geometry/Pastemask Top")
		(15 "B.Paste" user "Package Geometry/Pastemask Bottom")
		(5 "F.SilkS" user "Ref Des/Silkscreen Top")
		(7 "B.SilkS" user "Ref Des/Silkscreen Bottom")
		(1 "F.Mask" user "Board Geometry/Soldermask Top")
		(3 "B.Mask" user "Board Geometry/Soldermask Bottom")
		(17 "Dwgs.User" user "User.Drawings")
		(19 "Cmts.User" user "User.Comments")
		(21 "Eco1.User" user "User.Eco1")
		(23 "Eco2.User" user "User.Eco2")
		(25 "Edge.Cuts" user "Board Geometry/Outline")
		(27 "Margin" user)
		(31 "F.CrtYd" user "Package Geometry/Place Bound Top")
		(29 "B.CrtYd" user "Package Geometry/Place Bound Bottom")
		(35 "F.Fab" user "Ref Des/Assembly Top")
		(33 "B.Fab" user "Ref Des/Assembly Bottom")
	)
	(footprint ""
		(layer "F.Cu")
		(at 171.664122 -26.84399 90)
		(property "Reference" "PR4009"
			(at 0 0 90)
			(layer "F.SilkS")
			(hide yes)
			(effects
				(font
					(size 1.27 1.27)
				)
			)
		)
		(property "Value" ""
			(at 0 0 90)
			(layer "F.Fab")
			(effects
				(font
					(size 1.27 1.27)
				)
			)
		)
		(duplicate_pad_numbers_are_jumpers no)
		(fp_line
			(start 0.7874 -0.4064)
			(end 0.7874 0.4064)
			(stroke
				(width 0.1524)
				(type default)
			)
			(layer "F.SilkS")
		)
		(fp_line
			(start -0.7874 -0.4064)
			(end 0.7874 -0.4064)
			(stroke
				(width 0.1524)
				(type default)
			)
			(layer "F.SilkS")
		)
		(fp_line
			(start 0.7874 0.4064)
			(end -0.7874 0.4064)
			(stroke
				(width 0.1524)
				(type default)
			)
			(layer "F.SilkS")
		)
		(fp_line
			(start -0.7874 0.4064)
			(end -0.7874 -0.4064)
			(stroke
				(width 0.1524)
				(type default)
			)
			(layer "F.SilkS")
		)
		(fp_line
			(start -0.12065 -0.305054)
			(end -0.12065 -0.2794)
			(stroke
				(width 0.1)
				(type default)
			)
			(layer "F.Fab")
		)
		(fp_line
			(start -0.67945 -0.305054)
			(end -0.12065 -0.305054)
			(stroke
				(width 0.1)
				(type default)
			)
			(layer "F.Fab")
		)
		(fp_line
			(start 0.67945 -0.3048)
			(end 0.67945 0.3048)
			(stroke
				(width 0.1)
				(type default)
			)
			(layer "F.Fab")
		)
		(fp_line
			(start 0.12065 -0.3048)
			(end 0.67945 -0.3048)
			(stroke
				(width 0.1)
				(type default)
			)
			(layer "F.Fab")
		)
		(fp_line
			(start 0.12065 -0.2794)
			(end 0.12065 -0.3048)
			(stroke
				(width 0.1)
				(type default)
			)
			(layer "F.Fab")
		)
		(fp_line
			(start -0.12065 -0.2794)
			(end 0.12065 -0.2794)
			(stroke
				(width 0.1)
				(type default)
			)
			(layer "F.Fab")
		)
		(fp_line
			(start 0.120396 0.2794)
			(end -0.12065 0.2794)
			(stroke
				(width 0.1)
				(type default)
			)
			(layer "F.Fab")
		)
		(fp_line
			(start -0.12065 0.2794)
			(end -0.12065 0.3048)
			(stroke
				(width 0.1)
				(type default)
			)
			(layer "F.Fab")
		)
		(fp_line
			(start 0.67945 0.3048)
			(end 0.120396 0.3048)
			(stroke
				(width 0.1)
				(type default)
			)
			(layer "F.Fab")
		)
		(fp_line
			(start 0.120396 0.3048)
			(end 0.120396 0.2794)
			(stroke
				(width 0.1)
				(type default)
			)
			(layer "F.Fab")
		)
		(fp_line
			(start -0.12065 0.3048)
			(end -0.67945 0.3048)
			(stroke
				(width 0.1)
				(type default)
			)
			(layer "F.Fab")
		)
		(fp_line
			(start -0.67945 0.3048)
			(end -0.67945 -0.305054)
			(stroke
				(width 0.1)
				(type default)
			)
			(layer "F.Fab")
		)
		(pad "1" smd circle
			(at -0.40005 0 90)
			(size 0 0)
			(layers "F.Cu" "F.Mask" "F.Paste")
			(net "P12V_SCM_R")
		)
		(pad "2" smd circle
			(at 0.40005 0 90)
			(size 0 0)
			(layers "F.Cu" "F.Mask" "F.Paste")
			(net "P12V_SCM_OV_FB")
		)
	)
	(footprint ""
		(layer "F.Cu")
		(at 117.243352 -357.19766)
		(property "Reference" "ME17"
			(at 0 0 0)
			(layer "F.SilkS")
			(hide yes)
			(effects
				(font
					(size 1.27 1.27)
				)
			)
		)
		(property "Value" ""
			(at 0 0 0)
			(layer "F.Fab")
			(effects
				(font
					(size 1.27 1.27)
				)
			)
		)
		(duplicate_pad_numbers_are_jumpers no)
		(fp_line
			(start 0 -10.500106)
			(end 1.524 -10.500106)
			(stroke
				(width 0.1524)
				(type default)
			)
			(layer "F.SilkS")
		)
		(fp_line
			(start 0 -8.976106)
			(end 0 -10.500106)
			(stroke
				(width 0.1524)
				(type default)
			)
			(layer "F.SilkS")
		)
		(fp_line
			(start 0 0)
			(end 0 -1.524)
			(stroke
				(width 0.1524)
				(type default)
			)
			(layer "F.SilkS")
		)
		(fp_line
			(start 1.524 0)
			(end 0 0)
			(stroke
				(width 0.1524)
				(type default)
			)
			(layer "F.SilkS")
		)
		(fp_line
			(start 8.976106 0)
			(end 10.500106 0)
			(stroke
				(width 0.1524)
				(type default)
			)
			(layer "F.SilkS")
		)
		(fp_line
			(start 10.500106 -10.500106)
			(end 8.976106 -10.500106)
			(stroke
				(width 0.1524)
				(type default)
			)
			(layer "F.SilkS")
		)
		(fp_line
			(start 10.500106 -8.976106)
			(end 10.500106 -10.500106)
			(stroke
				(width 0.1524)
				(type default)
			)
			(layer "F.SilkS")
		)
		(fp_line
			(start 10.500106 0)
			(end 10.500106 -1.524)
			(stroke
				(width 0.1524)
				(type default)
			)
			(layer "F.SilkS")
		)
		(fp_text user "BIOS"
			(at 1.681226 -8.494776 0)
			(unlocked yes)
			(layer "F.SilkS")
			(effects
				(font
					(size 1.905 1.4224)
					(thickness 0.1524)
				)
				(justify left)
			)
		)
		(fp_text user "BMC"
			(at 2.303526 -1.865376 0)
			(unlocked yes)
			(layer "F.SilkS")
			(effects
				(font
					(size 1.905 1.4224)
					(thickness 0.1524)
				)
				(justify left)
			)
		)
		(fp_text user "&"
			(at 4.183126 -5.624576 0)
			(unlocked yes)
			(layer "F.SilkS")
			(effects
				(font
					(size 1.905 1.4224)
					(thickness 0.1524)
				)
				(justify left)
			)
		)
		(zone
			(layer "F.Cu")
			(hatch none 0.5)
			(connect_pads
				(clearance 0)
			)
			(min_thickness 0.25)
			(keepout
				(tracks not_allowed)
				(vias allowed)
				(pads allowed)
				(copperpour not_allowed)
				(footprints allowed)
			)
			(placement
				(enabled no)
				(sheetname "")
			)
			(fill
				(thermal_gap 0.5)
				(thermal_bridge_width 0.5)
				(island_removal_mode 0)
			)
			(polygon
				(pts
					(xy 117.243352 -357.19766) (xy 127.743458 -357.19766) (xy 127.743458 -367.697766) (xy 117.243352 -367.697766)
				)
			)
		)
	)
	(footprint ""
		(layer "F.Cu")
		(at 39.95039 -425.256706 180)
		(property "Reference" "C6008"
			(at 0 0 180)
			(layer "F.SilkS")
			(hide yes)
			(effects
				(font
					(size 1.27 1.27)
				)
			)
		)
		(property "Value" ""
			(at 0 0 180)
			(layer "F.Fab")
			(effects
				(font
					(size 1.27 1.27)
				)
			)
		)
		(duplicate_pad_numbers_are_jumpers no)
		(fp_line
			(start 0.7874 -0.4064)
			(end 0.7874 0.294894)
			(stroke
				(width 0.1524)
				(type default)
			)
			(layer "F.SilkS")
		)
		(fp_line
			(start -0.35941 0.4064)
			(end -0.7874 0.4064)
			(stroke
				(width 0.1524)
				(type default)
			)
			(layer "F.SilkS")
		)
		(fp_line
			(start -0.7874 -0.4064)
			(end 0.7874 -0.4064)
			(stroke
				(width 0.1524)
				(type default)
			)
			(layer "F.SilkS")
		)
		(fp_line
			(start 0.6858 0.3048)
			(end 0.1016 0.3048)
			(stroke
				(width 0.1)
				(type default)
			)
			(layer "F.Fab")
		)
		(fp_line
			(start 0.6858 -0.3048)
			(end 0.6858 0.3048)
			(stroke
				(width 0.1)
				(type default)
			)
			(layer "F.Fab")
		)
		(fp_line
			(start 0.1016 0.3048)
			(end 0.1016 0.2794)
			(stroke
				(width 0.1)
				(type default)
			)
			(layer "F.Fab")
		)
		(fp_line
			(start 0.1016 0.2794)
			(end -0.1016 0.2794)
			(stroke
				(width 0.1)
				(type default)
			)
			(layer "F.Fab")
		)
		(fp_line
			(start 0.1016 -0.2794)
			(end 0.1016 -0.3048)
			(stroke
				(width 0.1)
				(type default)
			)
			(layer "F.Fab")
		)
		(fp_line
			(start 0.1016 -0.3048)
			(end 0.6858 -0.3048)
			(stroke
				(width 0.1)
				(type default)
			)
			(layer "F.Fab")
		)
		(fp_line
			(start -0.1016 0.3048)
			(end -0.6858 0.3048)
			(stroke
				(width 0.1)
				(type default)
			)
			(layer "F.Fab")
		)
		(fp_line
			(start -0.1016 0.2794)
			(end -0.1016 0.3048)
			(stroke
				(width 0.1)
				(type default)
			)
			(layer "F.Fab")
		)
		(fp_line
			(start -0.1016 -0.2794)
			(end 0.1016 -0.2794)
			(stroke
				(width 0.1)
				(type default)
			)
			(layer "F.Fab")
		)
		(fp_line
			(start -0.1016 -0.3048)
			(end -0.1016 -0.2794)
			(stroke
				(width 0.1)
				(type default)
			)
			(layer "F.Fab")
		)
		(fp_line
			(start -0.6858 0.3048)
			(end -0.6858 -0.3048)
			(stroke
				(width 0.1)
				(type default)
			)
			(layer "F.Fab")
		)
		(fp_line
			(start -0.6858 -0.3048)
			(end -0.1016 -0.3048)
			(stroke
				(width 0.1)
				(type default)
			)
			(layer "F.Fab")
		)
		(pad "1" smd rect
			(at -0.40005 0)
			(size 0.4572 0.508)
			(layers "F.Cu" "F.Mask" "F.Paste")
			(net "P2E_MB_BMC_RX_BUF2_C_DN<0>")
		)
		(pad "2" smd rect
			(at 0.40005 0)
			(size 0.4572 0.508)
			(layers "F.Cu" "F.Mask" "F.Paste")
			(net "P2E_MB_BMC_RX_BUF_DN<0>")
		)
	)
	(footprint ""
		(layer "F.Cu")
		(at 263.017 -141.986 -90)
		(property "Reference" "R8007"
			(at 0 0 270)
			(layer "F.SilkS")
			(hide yes)
			(effects
				(font
					(size 1.27 1.27)
				)
			)
		)
		(property "Value" ""
			(at 0 0 270)
			(layer "F.Fab")
			(effects
				(font
					(size 1.27 1.27)
				)
			)
		)
		(duplicate_pad_numbers_are_jumpers no)
		(fp_line
			(start -0.7874 0.4064)
			(end -0.7874 -0.4064)
			(stroke
				(width 0.1524)
				(type default)
			)
			(layer "F.SilkS")
		)
		(fp_line
			(start 0.7874 0.4064)
			(end -0.7874 0.4064)
			(stroke
				(width 0.1524)
				(type default)
			)
			(layer "F.SilkS")
		)
		(fp_line
			(start -0.7874 -0.4064)
			(end 0.7874 -0.4064)
			(stroke
				(width 0.1524)
				(type default)
			)
			(layer "F.SilkS")
		)
		(fp_line
			(start 0.7874 -0.4064)
			(end 0.7874 0.4064)
			(stroke
				(width 0.1524)
				(type default)
			)
			(layer "F.SilkS")
		)
		(fp_line
			(start -0.67945 0.3048)
			(end -0.67945 -0.305054)
			(stroke
				(width 0.1)
				(type default)
			)
			(layer "F.Fab")
		)
		(fp_line
			(start -0.12065 0.3048)
			(end -0.67945 0.3048)
			(stroke
				(width 0.1)
				(type default)
			)
			(layer "F.Fab")
		)
		(fp_line
			(start 0.120396 0.3048)
			(end 0.120396 0.2794)
			(stroke
				(width 0.1)
				(type default)
			)
			(layer "F.Fab")
		)
		(fp_line
			(start 0.67945 0.3048)
			(end 0.120396 0.3048)
			(stroke
				(width 0.1)
				(type default)
			)
			(layer "F.Fab")
		)
		(fp_line
			(start -0.12065 0.2794)
			(end -0.12065 0.3048)
			(stroke
				(width 0.1)
				(type default)
			)
			(layer "F.Fab")
		)
		(fp_line
			(start 0.120396 0.2794)
			(end -0.12065 0.2794)
			(stroke
				(width 0.1)
				(type default)
			)
			(layer "F.Fab")
		)
		(fp_line
			(start -0.12065 -0.2794)
			(end 0.12065 -0.2794)
			(stroke
				(width 0.1)
				(type default)
			)
			(layer "F.Fab")
		)
		(fp_line
			(start 0.12065 -0.2794)
			(end 0.12065 -0.3048)
			(stroke
				(width 0.1)
				(type default)
			)
			(layer "F.Fab")
		)
		(fp_line
			(start 0.12065 -0.3048)
			(end 0.67945 -0.3048)
			(stroke
				(width 0.1)
				(type default)
			)
			(layer "F.Fab")
		)
		(fp_line
			(start 0.67945 -0.3048)
			(end 0.67945 0.3048)
			(stroke
				(width 0.1)
				(type default)
			)
			(layer "F.Fab")
		)
		(fp_line
			(start -0.67945 -0.305054)
			(end -0.12065 -0.305054)
			(stroke
				(width 0.1)
				(type default)
			)
			(layer "F.Fab")
		)
		(fp_line
			(start -0.12065 -0.305054)
			(end -0.12065 -0.2794)
			(stroke
				(width 0.1)
				(type default)
			)
			(layer "F.Fab")
		)
		(pad "1" smd circle
			(at -0.40005 0 270)
			(size 0 0)
			(layers "F.Cu" "F.Mask" "F.Paste")
			(net "SPI_CPU0_D0")
		)
		(pad "2" smd circle
			(at 0.40005 0 270)
			(size 0 0)
			(layers "F.Cu" "F.Mask" "F.Paste")
			(net "SPI_CPU0_R1_D0")
		)
	)
	(footprint ""
		(layer "F.Cu")
		(at 114.868706 -408.517344 -90)
		(property "Reference" "C6694"
			(at 0 0 270)
			(layer "F.SilkS")
			(hide yes)
			(effects
				(font
					(size 1.27 1.27)
				)
			)
		)
		(property "Value" ""
			(at 0 0 270)
			(layer "F.Fab")
			(effects
				(font
					(size 1.27 1.27)
				)
			)
		)
		(duplicate_pad_numbers_are_jumpers no)
		(fp_line
			(start -0.299974 0.150114)
			(end -0.299974 -0.150114)
			(stroke
				(width 0.1)
				(type default)
			)
			(layer "F.Fab")
		)
		(fp_line
			(start 0.299974 0.150114)
			(end -0.299974 0.150114)
			(stroke
				(width 0.1)
				(type default)
			)
			(layer "F.Fab")
		)
		(fp_line
			(start -0.299974 -0.150114)
			(end 0.299974 -0.150114)
			(stroke
				(width 0.1)
				(type default)
			)
			(layer "F.Fab")
		)
		(fp_line
			(start 0.299974 -0.150114)
			(end 0.299974 0.150114)
			(stroke
				(width 0.1)
				(type default)
			)
			(layer "F.Fab")
		)
		(pad "1" smd rect
			(at -0.2667 0 270)
			(size 0.3048 0.381)
			(layers "F.Cu" "F.Mask" "F.Paste")
			(net "P5E_CPU1_P2_TX_BUF_C_DN<0>")
		)
		(pad "2" smd rect
			(at 0.2667 0 270)
			(size 0.3048 0.381)
			(layers "F.Cu" "F.Mask" "F.Paste")
			(net "P5E_CPU1_P2_TX_BUF_DN<0>")
		)
	)
	(footprint ""
		(layer "F.Cu")
		(at 254.592836 -118.91645)
		(property "Reference" "R3725"
			(at 0 0 0)
			(layer "F.SilkS")
			(hide yes)
			(effects
				(font
					(size 1.27 1.27)
				)
			)
		)
		(property "Value" ""
			(at 0 0 0)
			(layer "F.Fab")
			(effects
				(font
					(size 1.27 1.27)
				)
			)
		)
		(duplicate_pad_numbers_are_jumpers no)
		(fp_line
			(start -0.7874 -0.4064)
			(end 0.7874 -0.4064)
			(stroke
				(width 0.1524)
				(type default)
			)
			(layer "F.SilkS")
		)
		(fp_line
			(start -0.7874 0.4064)
			(end -0.7874 -0.4064)
			(stroke
				(width 0.1524)
				(type default)
			)
			(layer "F.SilkS")
		)
		(fp_line
			(start 0.7874 -0.4064)
			(end 0.7874 0.4064)
			(stroke
				(width 0.1524)
				(type default)
			)
			(layer "F.SilkS")
		)
		(fp_line
			(start 0.7874 0.4064)
			(end -0.7874 0.4064)
			(stroke
				(width 0.1524)
				(type default)
			)
			(layer "F.SilkS")
		)
		(fp_line
			(start -0.67945 -0.305054)
			(end -0.12065 -0.305054)
			(stroke
				(width 0.1)
				(type default)
			)
			(layer "F.Fab")
		)
		(fp_line
			(start -0.67945 0.3048)
			(end -0.67945 -0.305054)
			(stroke
				(width 0.1)
				(type default)
			)
			(layer "F.Fab")
		)
		(fp_line
			(start -0.12065 -0.305054)
			(end -0.12065 -0.2794)
			(stroke
				(width 0.1)
				(type default)
			)
			(layer "F.Fab")
		)
		(fp_line
			(start -0.12065 -0.2794)
			(end 0.12065 -0.2794)
			(stroke
				(width 0.1)
				(type default)
			)
			(layer "F.Fab")
		)
		(fp_line
			(start -0.12065 0.2794)
			(end -0.12065 0.3048)
			(stroke
				(width 0.1)
				(type default)
			)
			(layer "F.Fab")
		)
		(fp_line
			(start -0.12065 0.3048)
			(end -0.67945 0.3048)
			(stroke
				(width 0.1)
				(type default)
			)
			(layer "F.Fab")
		)
		(fp_line
			(start 0.120396 0.2794)
			(end -0.12065 0.2794)
			(stroke
				(width 0.1)
				(type default)
			)
			(layer "F.Fab")
		)
		(fp_line
			(start 0.120396 0.3048)
			(end 0.120396 0.2794)
			(stroke
				(width 0.1)
				(type default)
			)
			(layer "F.Fab")
		)
		(fp_line
			(start 0.12065 -0.3048)
			(end 0.67945 -0.3048)
			(stroke
				(width 0.1)
				(type default)
			)
			(layer "F.Fab")
		)
		(fp_line
			(start 0.12065 -0.2794)
			(end 0.12065 -0.3048)
			(stroke
				(width 0.1)
				(type default)
			)
			(layer "F.Fab")
		)
		(fp_line
			(start 0.67945 -0.3048)
			(end 0.67945 0.3048)
			(stroke
				(width 0.1)
				(type default)
			)
			(layer "F.Fab")
		)
		(fp_line
			(start 0.67945 0.3048)
			(end 0.120396 0.3048)
			(stroke
				(width 0.1)
				(type default)
			)
			(layer "F.Fab")
		)
		(pad "1" smd circle
			(at -0.40005 0)
			(size 0 0)
			(layers "F.Cu" "F.Mask" "F.Paste")
			(net "P3V3_AUX")
		)
		(pad "2" smd circle
			(at 0.40005 0)
			(size 0 0)
			(layers "F.Cu" "F.Mask" "F.Paste")
			(net "SMB_LM75_0_3V3AUX_SCL")
		)
	)
	(footprint ""
		(layer "F.Cu")
		(at 412.23184 -381.41783 -90)
		(property "Reference" "C853"
			(at 0 0 270)
			(layer "F.SilkS")
			(hide yes)
			(effects
				(font
					(size 1.27 1.27)
				)
			)
		)
		(property "Value" ""
			(at 0 0 270)
			(layer "F.Fab")
			(effects
				(font
					(size 1.27 1.27)
				)
			)
		)
		(duplicate_pad_numbers_are_jumpers no)
		(fp_line
			(start -0.299974 0.150114)
			(end -0.299974 -0.150114)
			(stroke
				(width 0.1)
				(type default)
			)
			(layer "F.Fab")
		)
		(fp_line
			(start 0.299974 0.150114)
			(end -0.299974 0.150114)
			(stroke
				(width 0.1)
				(type default)
			)
			(layer "F.Fab")
		)
		(fp_line
			(start -0.299974 -0.150114)
			(end 0.299974 -0.150114)
			(stroke
				(width 0.1)
				(type default)
			)
			(layer "F.Fab")
		)
		(fp_line
			(start 0.299974 -0.150114)
			(end 0.299974 0.150114)
			(stroke
				(width 0.1)
				(type default)
			)
			(layer "F.Fab")
		)
		(pad "1" smd rect
			(at -0.2667 0 270)
			(size 0.3048 0.381)
			(layers "F.Cu" "F.Mask" "F.Paste")
			(net "P5E_CPU0_P2_TX_C_DP<8>")
		)
		(pad "2" smd rect
			(at 0.2667 0 270)
			(size 0.3048 0.381)
			(layers "F.Cu" "F.Mask" "F.Paste")
			(net "P5E_CPU0_P2_TX_DP<8>")
		)
	)
)
